# T6G (Grand Teton) — schematic netlist excerpt (pin names and nets, part order shuffled) for the footprints in the layout excerpt that follows; sources: Cadence DE-HDL packaged netlist, KiCad conversion of 04192023_DAF0TMB3IC0_F0TG_MB_C_brd_V02_OCP.brd

C6699  Q_CAP_DIFFBUS  DIFF BUS_0.22UF 6.3V 20% X6S  pkg C0201  page 341 : \1\ = P5E_CPU1_P2_TX_BUF_C_DP<3> ; \2\ = P5E_CPU1_P2_TX_BUF_DP<3>
C1975  Q_CAP  0.1UF 25V 10% X7R  pkg 0402  page 126 : A = GPU_HMC_PRSNT_ISO_N ; B = GND
PC609_3  Q_CAP  0.1UF 25V 10% X7R  pkg 0402  page 199 : A = SW_P12V_AUX_PVDDCR_SOC_P0_FLT ; B = GND

(kicad_pcb
	(version 20260206)
	(generator "pcbnew")
	(generator_version "10.0")
	(general
		(thickness 1.6)
		(legacy_teardrops no)
	)
	(paper "A4")
	(title_block
		(title "04192023_DAF0TMB3IC0_F0TG_MB_C_brd_V02_OCP.brd")
		(comment 1 "Grand Teton / footprints 4139-4141 of 8354")
	)
	(layers
		(0 "F.Cu" signal "TOP")
		(4 "In1.Cu" signal "GND")
		(6 "In2.Cu" signal "IN1")
		(8 "In3.Cu" signal "GND1")
		(10 "In4.Cu" signal "IN2")
		(12 "In5.Cu" signal "GND2")
		(14 "In6.Cu" signal "IN3")
		(16 "In7.Cu" signal "GND3")
		(18 "In8.Cu" signal "VCC")
		(20 "In9.Cu" signal "VCC1")
		(22 "In10.Cu" signal "GND4")
		(24 "In11.Cu" signal "IN4")
		(26 "In12.Cu" signal "GND5")
		(28 "In13.Cu" signal "IN5")
		(30 "In14.Cu" signal "GND6")
		(32 "In15.Cu" signal "IN6")
		(34 "In16.Cu" signal "GND7")
		(2 "B.Cu" signal "BOTTOM")
		(9 "F.Adhes" user "F.Adhesive")
		(11 "B.Adhes" user "B.Adhesive")
		(13 "F.Paste" user "Package Geometry/Pastemask Top")
		(15 "B.Paste" user "Package Geometry/Pastemask Bottom")
		(5 "F.SilkS" user "Ref Des/Silkscreen Top")
		(7 "B.SilkS" user "Ref Des/Silkscreen Bottom")
		(1 "F.Mask" user "Board Geometry/Soldermask Top")
		(3 "B.Mask" user "Board Geometry/Soldermask Bottom")
		(17 "Dwgs.User" user "User.Drawings")
		(19 "Cmts.User" user "User.Comments")
		(21 "Eco1.User" user "User.Eco1")
		(23 "Eco2.User" user "User.Eco2")
		(25 "Edge.Cuts" user "Board Geometry/Outline")
		(27 "Margin" user)
		(31 "F.CrtYd" user "Package Geometry/Place Bound Top")
		(29 "B.CrtYd" user "Package Geometry/Place Bound Bottom")
		(35 "F.Fab" user "Ref Des/Assembly Top")
		(33 "B.Fab" user "Ref Des/Assembly Bottom")
	)
	(footprint ""
		(layer "F.Cu")
		(at 409.853638 -163.684966 90)
		(property "Reference" "PC609_3"
			(at 0 0 90)
			(layer "F.SilkS")
			(hide yes)
			(effects
				(font
					(size 1.27 1.27)
				)
			)
		)
		(property "Value" ""
			(at 0 0 90)
			(layer "F.Fab")
			(effects
				(font
					(size 1.27 1.27)
				)
			)
		)
		(duplicate_pad_numbers_are_jumpers no)
		(fp_line
			(start 0.7874 -0.4064)
			(end 0.7874 0.4064)
			(stroke
				(width 0.1524)
				(type default)
			)
			(layer "F.SilkS")
		)
		(fp_line
			(start -0.7874 -0.4064)
			(end 0.7874 -0.4064)
			(stroke
				(width 0.1524)
				(type default)
			)
			(layer "F.SilkS")
		)
		(fp_line
			(start 0.7874 0.4064)
			(end -0.7874 0.4064)
			(stroke
				(width 0.1524)
				(type default)
			)
			(layer "F.SilkS")
		)
		(fp_line
			(start -0.7874 0.4064)
			(end -0.7874 -0.4064)
			(stroke
				(width 0.1524)
				(type default)
			)
			(layer "F.SilkS")
		)
		(fp_line
			(start -0.12065 -0.305054)
			(end -0.12065 -0.2794)
			(stroke
				(width 0.1)
				(type default)
			)
			(layer "F.Fab")
		)
		(fp_line
			(start -0.67945 -0.305054)
			(end -0.12065 -0.305054)
			(stroke
				(width 0.1)
				(type default)
			)
			(layer "F.Fab")
		)
		(fp_line
			(start 0.67945 -0.3048)
			(end 0.67945 0.3048)
			(stroke
				(width 0.1)
				(type default)
			)
			(layer "F.Fab")
		)
		(fp_line
			(start 0.12065 -0.3048)
			(end 0.67945 -0.3048)
			(stroke
				(width 0.1)
				(type default)
			)
			(layer "F.Fab")
		)
		(fp_line
			(start 0.12065 -0.2794)
			(end 0.12065 -0.3048)
			(stroke
				(width 0.1)
				(type default)
			)
			(layer "F.Fab")
		)
		(fp_line
			(start -0.12065 -0.2794)
			(end 0.12065 -0.2794)
			(stroke
				(width 0.1)
				(type default)
			)
			(layer "F.Fab")
		)
		(fp_line
			(start 0.120396 0.2794)
			(end -0.12065 0.2794)
			(stroke
				(width 0.1)
				(type default)
			)
			(layer "F.Fab")
		)
		(fp_line
			(start -0.12065 0.2794)
			(end -0.12065 0.3048)
			(stroke
				(width 0.1)
				(type default)
			)
			(layer "F.Fab")
		)
		(fp_line
			(start 0.67945 0.3048)
			(end 0.120396 0.3048)
			(stroke
				(width 0.1)
				(type default)
			)
			(layer "F.Fab")
		)
		(fp_line
			(start 0.120396 0.3048)
			(end 0.120396 0.2794)
			(stroke
				(width 0.1)
				(type default)
			)
			(layer "F.Fab")
		)
		(fp_line
			(start -0.12065 0.3048)
			(end -0.67945 0.3048)
			(stroke
				(width 0.1)
				(type default)
			)
			(layer "F.Fab")
		)
		(fp_line
			(start -0.67945 0.3048)
			(end -0.67945 -0.305054)
			(stroke
				(width 0.1)
				(type default)
			)
			(layer "F.Fab")
		)
		(pad "1" smd circle
			(at -0.40005 0 90)
			(size 0 0)
			(layers "F.Cu" "F.Mask" "F.Paste")
			(net "SW_P12V_AUX_PVDDCR_SOC_P0_FLT")
		)
		(pad "2" smd circle
			(at 0.40005 0 90)
			(size 0 0)
			(layers "F.Cu" "F.Mask" "F.Paste")
			(net "GND")
		)
	)
	(footprint ""
		(layer "F.Cu")
		(at 124.972826 -408.517344 -90)
		(property "Reference" "C6699"
			(at 0 0 270)
			(layer "F.SilkS")
			(hide yes)
			(effects
				(font
					(size 1.27 1.27)
				)
			)
		)
		(property "Value" ""
			(at 0 0 270)
			(layer "F.Fab")
			(effects
				(font
					(size 1.27 1.27)
				)
			)
		)
		(duplicate_pad_numbers_are_jumpers no)
		(fp_line
			(start -0.299974 0.150114)
			(end -0.299974 -0.150114)
			(stroke
				(width 0.1)
				(type default)
			)
			(layer "F.Fab")
		)
		(fp_line
			(start 0.299974 0.150114)
			(end -0.299974 0.150114)
			(stroke
				(width 0.1)
				(type default)
			)
			(layer "F.Fab")
		)
		(fp_line
			(start -0.299974 -0.150114)
			(end 0.299974 -0.150114)
			(stroke
				(width 0.1)
				(type default)
			)
			(layer "F.Fab")
		)
		(fp_line
			(start 0.299974 -0.150114)
			(end 0.299974 0.150114)
			(stroke
				(width 0.1)
				(type default)
			)
			(layer "F.Fab")
		)
		(pad "1" smd rect
			(at -0.2667 0 270)
			(size 0.3048 0.381)
			(layers "F.Cu" "F.Mask" "F.Paste")
			(net "P5E_CPU1_P2_TX_BUF_C_DP<3>")
		)
		(pad "2" smd rect
			(at 0.2667 0 270)
			(size 0.3048 0.381)
			(layers "F.Cu" "F.Mask" "F.Paste")
			(net "P5E_CPU1_P2_TX_BUF_DP<3>")
		)
	)
	(footprint ""
		(layer "F.Cu")
		(at 118.491 -420.497 180)
		(property "Reference" "C1975"
			(at 0 0 180)
			(layer "F.SilkS")
			(hide yes)
			(effects
				(font
					(size 1.27 1.27)
				)
			)
		)
		(property "Value" ""
			(at 0 0 180)
			(layer "F.Fab")
			(effects
				(font
					(size 1.27 1.27)
				)
			)
		)
		(duplicate_pad_numbers_are_jumpers no)
		(fp_line
			(start 0.7874 0.4064)
			(end -0.7874 0.4064)
			(stroke
				(width 0.1524)
				(type default)
			)
			(layer "F.SilkS")
		)
		(fp_line
			(start 0.7874 -0.4064)
			(end 0.7874 0.4064)
			(stroke
				(width 0.1524)
				(type default)
			)
			(layer "F.SilkS")
		)
		(fp_line
			(start -0.7874 0.4064)
			(end -0.7874 -0.4064)
			(stroke
				(width 0.1524)
				(type default)
			)
			(layer "F.SilkS")
		)
		(fp_line
			(start -0.7874 -0.4064)
			(end 0.7874 -0.4064)
			(stroke
				(width 0.1524)
				(type default)
			)
			(layer "F.SilkS")
		)
		(fp_line
			(start 0.67945 0.3048)
			(end 0.120396 0.3048)
			(stroke
				(width 0.1)
				(type default)
			)
			(layer "F.Fab")
		)
		(fp_line
			(start 0.67945 -0.3048)
			(end 0.67945 0.3048)
			(stroke
				(width 0.1)
				(type default)
			)
			(layer "F.Fab")
		)
		(fp_line
			(start 0.12065 -0.2794)
			(end 0.12065 -0.3048)
			(stroke
				(width 0.1)
				(type default)
			)
			(layer "F.Fab")
		)
		(fp_line
			(start 0.12065 -0.3048)
			(end 0.67945 -0.3048)
			(stroke
				(width 0.1)
				(type default)
			)
			(layer "F.Fab")
		)
		(fp_line
			(start 0.120396 0.3048)
			(end 0.120396 0.2794)
			(stroke
				(width 0.1)
				(type default)
			)
			(layer "F.Fab")
		)
		(fp_line
			(start 0.120396 0.2794)
			(end -0.12065 0.2794)
			(stroke
				(width 0.1)
				(type default)
			)
			(layer "F.Fab")
		)
		(fp_line
			(start -0.12065 0.3048)
			(end -0.67945 0.3048)
			(stroke
				(width 0.1)
				(type default)
			)
			(layer "F.Fab")
		)
		(fp_line
			(start -0.12065 0.2794)
			(end -0.12065 0.3048)
			(stroke
				(width 0.1)
				(type default)
			)
			(layer "F.Fab")
		)
		(fp_line
			(start -0.12065 -0.2794)
			(end 0.12065 -0.2794)
			(stroke
				(width 0.1)
				(type default)
			)
			(layer "F.Fab")
		)
		(fp_line
			(start -0.12065 -0.305054)
			(end -0.12065 -0.2794)
			(stroke
				(width 0.1)
				(type default)
			)
			(layer "F.Fab")
		)
		(fp_line
			(start -0.67945 0.3048)
			(end -0.67945 -0.305054)
			(stroke
				(width 0.1)
				(type default)
			)
			(layer "F.Fab")
		)
		(fp_line
			(start -0.67945 -0.305054)
			(end -0.12065 -0.305054)
			(stroke
				(width 0.1)
				(type default)
			)
			(layer "F.Fab")
		)
		(pad "1" smd circle
			(at -0.40005 0 180)
			(size 0 0)
			(layers "F.Cu" "F.Mask" "F.Paste")
			(net "GPU_HMC_PRSNT_ISO_N")
		)
		(pad "2" smd circle
			(at 0.40005 0 180)
			(size 0 0)
			(layers "F.Cu" "F.Mask" "F.Paste")
			(net "GND")
		)
	)
)
